(kicad_pcb
	(version 20260206)
	(generator "pcbnew")
	(generator_version "10.0")
	(general
		(thickness 1.6)
		(legacy_teardrops no)
	)
	(paper "A4")
	(title_block
		(title "dpb — 14545-sa.0730WZS0815.brd")
		(comment 1 "Honey Badger (Wiwynn) / footprints 1066-1066 of 1066")
	)
	(layers
		(0 "F.Cu" signal "TOP")
		(4 "In1.Cu" signal "L2GND")
		(6 "In2.Cu" signal "L3")
		(8 "In3.Cu" signal "L4VCC")
		(10 "In4.Cu" signal "L5VCC")
		(12 "In5.Cu" signal "L6")
		(14 "In6.Cu" signal "L7GND")
		(2 "B.Cu" signal "BOTTOM")
		(9 "F.Adhes" user "F.Adhesive")
		(11 "B.Adhes" user "B.Adhesive")
		(13 "F.Paste" user "Package Geometry/Pastemask Top")
		(15 "B.Paste" user "Package Geometry/Pastemask Bottom")
		(5 "F.SilkS" user "Ref Des/Silkscreen Top")
		(7 "B.SilkS" user "Ref Des/Silkscreen Bottom")
		(1 "F.Mask" user "Board Geometry/Soldermask Top")
		(3 "B.Mask" user "Board Geometry/Soldermask Bottom")
		(17 "Dwgs.User" user "User.Drawings")
		(19 "Cmts.User" user "User.Comments")
		(21 "Eco1.User" user "User.Eco1")
		(23 "Eco2.User" user "User.Eco2")
		(25 "Edge.Cuts" user "Board Geometry/Outline")
		(27 "Margin" user)
		(31 "F.CrtYd" user "Package Geometry/Place Bound Top")
		(29 "B.CrtYd" user "Package Geometry/Place Bound Bottom")
		(35 "F.Fab" user "Ref Des/Assembly Top")
		(33 "B.Fab" user "Ref Des/Assembly Bottom")
	)
	(footprint ""
		(layer "F.Cu")
		(at 71.754746 -396.5067)
		(property "Reference" "R447"
			(at 0 0 0)
			(layer "F.SilkS")
			(hide yes)
			(effects
				(font
					(size 1.27 1.27)
				)
			)
		)
		(property "Value" "4K7R2J-2-GP"
			(at 0.064008 -3.993896 0)
			(unlocked yes)
			(layer "F.Fab")
			(hide yes)
			(effects
				(font
					(size 1.016 1.016)
					(thickness 0.1524)
				)
			)
		)
		(property "Device Type" "R402H16"
			(at 0.064008 -5.517896 0)
			(unlocked yes)
			(layer "F.Fab")
			(hide yes)
			(effects
				(font
					(size 1.016 1.016)
					(thickness 0.1524)
				)
			)
		)
		(duplicate_pad_numbers_are_jumpers no)
		(fp_line
			(start -0.508 -0.9398)
			(end -0.508 0.9398)
			(stroke
				(width 0.1524)
				(type default)
			)
			(layer "F.SilkS")
		)
		(fp_line
			(start 0.508 -0.9398)
			(end -0.508 -0.9398)
			(stroke
				(width 0.1524)
				(type default)
			)
			(layer "F.SilkS")
		)
		(fp_rect
			(start -0.508 0.9398)
			(end 0.508 -0.9398)
			(stroke
				(width 0)
				(type default)
			)
			(fill no)
			(layer "F.CrtYd")
		)
		(fp_rect
			(start -0.508 0.9398)
			(end 0.508 -0.9398)
			(stroke
				(width 0)
				(type default)
			)
			(fill no)
			(layer "F.Fab")
		)
		(pad "1" smd custom
			(at 0 -0.4445)
			(size 0.1397 0.1397)
			(layers "F.Cu" "F.Mask" "F.Paste")
			(net "P3V3")
			(options
				(clearance outline)
				(anchor circle)
			)
			(primitives
				(gr_poly
					(pts
						(arc
							(start -0.1778 -0.2794)
							(mid -0.249642 -0.249642)
							(end -0.2794 -0.1778)
						)
						(arc
							(start -0.2794 0.1778)
							(mid -0.249642 0.249642)
							(end -0.1778 0.2794)
						)
						(arc
							(start 0.1778 0.2794)
							(mid 0.249642 0.249642)
							(end 0.2794 0.1778)
						)
						(arc
							(start 0.2794 -0.1778)
							(mid 0.249642 -0.249642)
							(end 0.1778 -0.2794)
						)
					)
					(width 0)
					(fill yes)
				)
			)
		)
		(pad "2" smd custom
			(at 0 0.4445)
			(size 0.1397 0.1397)
			(layers "F.Cu" "F.Mask" "F.Paste")
			(net "SAS2X28_B_HDD6_FLT")
			(options
				(clearance outline)
				(anchor circle)
			)
			(primitives
				(gr_poly
					(pts
						(arc
							(start -0.1778 -0.2794)
							(mid -0.249642 -0.249642)
							(end -0.2794 -0.1778)
						)
						(arc
							(start -0.2794 0.1778)
							(mid -0.249642 0.249642)
							(end -0.1778 0.2794)
						)
						(arc
							(start 0.1778 0.2794)
							(mid 0.249642 0.249642)
							(end 0.2794 0.1778)
						)
						(arc
							(start 0.2794 -0.1778)
							(mid 0.249642 -0.249642)
							(end 0.1778 -0.2794)
						)
					)
					(width 0)
					(fill yes)
				)
			)
		)
	)
)
